# BASEBOARD_FAB2 (Tioga Pass) — schematic netlist excerpt (pin names and nets, part order shuffled) for the footprints in the layout excerpt that follows; sources: Cadence DE-HDL packaged netlist, KiCad conversion of Wiwynn_Tioga_Pass_MB.brd

C1G13  CAP  1.0UF 16V 10% X6S  pkg 0402  page 224 : A = VR_FET_SW_P12V_STBY_PVDDQ_GHJ ; B = GND
R1L38  RES  1.00K 1% CHIP  pkg 0402  page 168 : A = P3V3_STBY ; B = FM_POST_CARD_PRES_BMC_N
R6P7  RES  42.2 1.0% EMPTY  pkg 0402  page 103 : A = CLK_100M_CPU1_BCLK1_DP ; B = GND

(kicad_pcb
	(version 20260206)
	(generator "pcbnew")
	(generator_version "10.0")
	(general
		(thickness 1.6)
		(legacy_teardrops no)
	)
	(paper "A4")
	(title_block
		(title "Wiwynn_Tioga_Pass_MB.brd")
		(comment 1 "Tioga Pass / footprints 3852-3854 of 4770")
	)
	(layers
		(0 "F.Cu" signal "TOP")
		(4 "In1.Cu" signal "L2GND")
		(6 "In2.Cu" signal "L3")
		(8 "In3.Cu" signal "L4GND")
		(10 "In4.Cu" signal "L5")
		(12 "In5.Cu" signal "L6GND")
		(14 "In6.Cu" signal "L7VCC")
		(16 "In7.Cu" signal "L8VCC")
		(18 "In8.Cu" signal "L9GND")
		(20 "In9.Cu" signal "L10")
		(22 "In10.Cu" signal "L11GND")
		(24 "In11.Cu" signal "L12")
		(26 "In12.Cu" signal "L13GND")
		(2 "B.Cu" signal "BOTTOM")
		(9 "F.Adhes" user "F.Adhesive")
		(11 "B.Adhes" user "B.Adhesive")
		(13 "F.Paste" user "Package Geometry/Pastemask Top")
		(15 "B.Paste" user "Package Geometry/Pastemask Bottom")
		(5 "F.SilkS" user "Ref Des/Silkscreen Top")
		(7 "B.SilkS" user "Ref Des/Silkscreen Bottom")
		(1 "F.Mask" user "Board Geometry/Soldermask Top")
		(3 "B.Mask" user "Board Geometry/Soldermask Bottom")
		(17 "Dwgs.User" user "User.Drawings")
		(19 "Cmts.User" user "User.Comments")
		(21 "Eco1.User" user "User.Eco1")
		(23 "Eco2.User" user "User.Eco2")
		(25 "Edge.Cuts" user "Board Geometry/Outline")
		(27 "Margin" user)
		(31 "F.CrtYd" user "Package Geometry/Place Bound Top")
		(29 "B.CrtYd" user "Package Geometry/Place Bound Bottom")
		(35 "F.Fab" user "Ref Des/Assembly Top")
		(33 "B.Fab" user "Ref Des/Assembly Bottom")
	)
	(footprint ""
		(layer "B.Cu")
		(at 166.116 -87.757)
		(property "Reference" "R6P7"
			(at 0 0 0)
			(layer "B.SilkS")
			(hide yes)
			(effects
				(font
					(size 1.27 1.27)
				)
				(justify mirror)
			)
		)
		(property "Value" ""
			(at 0 0 0)
			(layer "B.Fab")
			(effects
				(font
					(size 1.27 1.27)
				)
				(justify mirror)
			)
		)
		(duplicate_pad_numbers_are_jumpers no)
		(fp_poly
			(pts
				(xy 0.2794 -0.1016) (xy -0.2794 -0.1016) (xy -0.2794 0.9906) (xy 0.2794 0.9906)
			)
			(stroke
				(width 0)
				(type default)
			)
			(fill no)
			(layer "B.CrtYd")
		)
		(fp_line
			(start -0.2794 -0.1016)
			(end 0.2794 -0.1016)
			(stroke
				(width 0.1)
				(type default)
			)
			(layer "B.Fab")
		)
		(fp_line
			(start -0.2794 0.9906)
			(end -0.2794 -0.1016)
			(stroke
				(width 0.1)
				(type default)
			)
			(layer "B.Fab")
		)
		(fp_line
			(start 0.2794 -0.1016)
			(end 0.2794 0.9906)
			(stroke
				(width 0.1)
				(type default)
			)
			(layer "B.Fab")
		)
		(fp_line
			(start 0.2794 0.9906)
			(end -0.2794 0.9906)
			(stroke
				(width 0.1)
				(type default)
			)
			(layer "B.Fab")
		)
		(pad "1" smd rect
			(at 0 0 180)
			(size 0.508 0.508)
			(layers "B.Cu" "B.Mask" "B.Paste")
			(net "CLK_100M_CPU1_BCLK1_DP")
		)
		(pad "2" smd rect
			(at 0 0.889 180)
			(size 0.508 0.508)
			(layers "B.Cu" "B.Mask" "B.Paste")
			(net "GND")
		)
		(zone
			(layer "B.Cu")
			(hatch none 0.5)
			(connect_pads
				(clearance 0)
			)
			(min_thickness 0.25)
			(keepout
				(tracks allowed)
				(vias not_allowed)
				(pads allowed)
				(copperpour not_allowed)
				(footprints allowed)
			)
			(placement
				(enabled no)
				(sheetname "")
			)
			(fill
				(thermal_gap 0.5)
				(thermal_bridge_width 0.5)
				(island_removal_mode 0)
			)
			(polygon
				(pts
					(xy 166.37 -87.503) (xy 165.862 -87.503) (xy 165.862 -87.122) (xy 166.37 -87.122)
				)
			)
		)
		(zone
			(layer "B.Cu")
			(hatch none 0.5)
			(connect_pads
				(clearance 0)
			)
			(min_thickness 0.25)
			(keepout
				(tracks not_allowed)
				(vias allowed)
				(pads allowed)
				(copperpour not_allowed)
				(footprints allowed)
			)
			(placement
				(enabled no)
				(sheetname "")
			)
			(fill
				(thermal_gap 0.5)
				(thermal_bridge_width 0.5)
				(island_removal_mode 0)
			)
			(polygon
				(pts
					(xy 166.37 -87.122) (xy 165.862 -87.122) (xy 165.862 -87.503) (xy 166.37 -87.503)
				)
			)
		)
	)
	(footprint ""
		(layer "B.Cu")
		(at 487.172 -139.6746 90)
		(property "Reference" "R1L38"
			(at 0 0 90)
			(layer "B.SilkS")
			(hide yes)
			(effects
				(font
					(size 1.27 1.27)
				)
				(justify mirror)
			)
		)
		(property "Value" ""
			(at 0 0 90)
			(layer "B.Fab")
			(effects
				(font
					(size 1.27 1.27)
				)
				(justify mirror)
			)
		)
		(duplicate_pad_numbers_are_jumpers no)
		(fp_poly
			(pts
				(xy 0.2794 -0.1016) (xy -0.2794 -0.1016) (xy -0.2794 0.9906) (xy 0.2794 0.9906)
			)
			(stroke
				(width 0)
				(type default)
			)
			(fill no)
			(layer "B.CrtYd")
		)
		(fp_line
			(start 0.2794 -0.1016)
			(end 0.2794 0.9906)
			(stroke
				(width 0.1)
				(type default)
			)
			(layer "B.Fab")
		)
		(fp_line
			(start -0.2794 -0.1016)
			(end 0.2794 -0.1016)
			(stroke
				(width 0.1)
				(type default)
			)
			(layer "B.Fab")
		)
		(fp_line
			(start 0.2794 0.9906)
			(end -0.2794 0.9906)
			(stroke
				(width 0.1)
				(type default)
			)
			(layer "B.Fab")
		)
		(fp_line
			(start -0.2794 0.9906)
			(end -0.2794 -0.1016)
			(stroke
				(width 0.1)
				(type default)
			)
			(layer "B.Fab")
		)
		(pad "1" smd rect
			(at 0 0 270)
			(size 0.508 0.508)
			(layers "B.Cu" "B.Mask" "B.Paste")
			(net "P3V3_STBY")
		)
		(pad "2" smd rect
			(at 0 0.889 270)
			(size 0.508 0.508)
			(layers "B.Cu" "B.Mask" "B.Paste")
			(net "FM_POST_CARD_PRES_BMC_N")
		)
		(zone
			(layer "B.Cu")
			(hatch none 0.5)
			(connect_pads
				(clearance 0)
			)
			(min_thickness 0.25)
			(keepout
				(tracks allowed)
				(vias not_allowed)
				(pads allowed)
				(copperpour not_allowed)
				(footprints allowed)
			)
			(placement
				(enabled no)
				(sheetname "")
			)
			(fill
				(thermal_gap 0.5)
				(thermal_bridge_width 0.5)
				(island_removal_mode 0)
			)
			(polygon
				(pts
					(xy 487.426 -139.9286) (xy 487.426 -139.4206) (xy 487.807 -139.4206) (xy 487.807 -139.9286)
				)
			)
		)
		(zone
			(layer "B.Cu")
			(hatch none 0.5)
			(connect_pads
				(clearance 0)
			)
			(min_thickness 0.25)
			(keepout
				(tracks not_allowed)
				(vias allowed)
				(pads allowed)
				(copperpour not_allowed)
				(footprints allowed)
			)
			(placement
				(enabled no)
				(sheetname "")
			)
			(fill
				(thermal_gap 0.5)
				(thermal_bridge_width 0.5)
				(island_removal_mode 0)
			)
			(polygon
				(pts
					(xy 487.807 -139.9286) (xy 487.807 -139.4206) (xy 487.426 -139.4206) (xy 487.426 -139.9286)
				)
			)
		)
	)
	(footprint ""
		(layer "B.Cu")
		(at 4.25704 -12.573 90)
		(property "Reference" "C1G13"
			(at 0 0 90)
			(layer "B.SilkS")
			(hide yes)
			(effects
				(font
					(size 1.27 1.27)
				)
				(justify mirror)
			)
		)
		(property "Value" ""
			(at 0 0 90)
			(layer "B.Fab")
			(effects
				(font
					(size 1.27 1.27)
				)
				(justify mirror)
			)
		)
		(duplicate_pad_numbers_are_jumpers no)
		(fp_poly
			(pts
				(xy -0.3048 -0.1016) (xy -0.3048 0.9906) (xy 0.3048 0.9906) (xy 0.3048 -0.1016)
			)
			(stroke
				(width 0)
				(type default)
			)
			(fill no)
			(layer "B.CrtYd")
		)
		(fp_line
			(start 0.3048 -0.1016)
			(end 0.3048 0.9906)
			(stroke
				(width 0.1)
				(type default)
			)
			(layer "B.Fab")
		)
		(fp_line
			(start -0.3048 -0.1016)
			(end 0.3048 -0.1016)
			(stroke
				(width 0.1)
				(type default)
			)
			(layer "B.Fab")
		)
		(fp_line
			(start 0.3048 0.9906)
			(end -0.3048 0.9906)
			(stroke
				(width 0.1)
				(type default)
			)
			(layer "B.Fab")
		)
		(fp_line
			(start -0.3048 0.9906)
			(end -0.3048 -0.1016)
			(stroke
				(width 0.1)
				(type default)
			)
			(layer "B.Fab")
		)
		(pad "1" smd rect
			(at 0 0 270)
			(size 0.508 0.508)
			(layers "B.Cu" "B.Mask" "B.Paste")
			(net "VR_FET_SW_P12V_STBY_PVDDQ_GHJ")
		)
		(pad "2" smd rect
			(at 0 0.889 270)
			(size 0.508 0.508)
			(layers "B.Cu" "B.Mask" "B.Paste")
			(net "GND")
		)
		(zone
			(layer "B.Cu")
			(hatch none 0.5)
			(connect_pads
				(clearance 0)
			)
			(min_thickness 0.25)
			(keepout
				(tracks allowed)
				(vias not_allowed)
				(pads allowed)
				(copperpour not_allowed)
				(footprints allowed)
			)
			(placement
				(enabled no)
				(sheetname "")
			)
			(fill
				(thermal_gap 0.5)
				(thermal_bridge_width 0.5)
				(island_removal_mode 0)
			)
			(polygon
				(pts
					(xy 4.51104 -12.827) (xy 4.51104 -12.319) (xy 4.89204 -12.319) (xy 4.89204 -12.827)
				)
			)
		)
		(zone
			(layer "B.Cu")
			(hatch none 0.5)
			(connect_pads
				(clearance 0)
			)
			(min_thickness 0.25)
			(keepout
				(tracks not_allowed)
				(vias allowed)
				(pads allowed)
				(copperpour not_allowed)
				(footprints allowed)
			)
			(placement
				(enabled no)
				(sheetname "")
			)
			(fill
				(thermal_gap 0.5)
				(thermal_bridge_width 0.5)
				(island_removal_mode 0)
			)
			(polygon
				(pts
					(xy 4.89204 -12.827) (xy 4.89204 -12.319) (xy 4.51104 -12.319) (xy 4.51104 -12.827)
				)
			)
		)
	)
)
